FILE_TYPE=LIBRARY_PARTS;
primitive 'SPRINGVILLE','SPRINGVILLE_SMT';
  pin
    'AVDD10':
      PIN_NUMBER='(38)';
      PINUSE='POWER';
      NO_LOAD_CHECK='Both';
      NO_IO_CHECK='Both';
      NO_ASSERT_CHECK='TRUE';
      NO_DIR_CHECK='TRUE';
      ALLOW_CONNECT='TRUE';
    'AVDD1P5'<2>:
      PIN_NUMBER='(39)';
      PINUSE='POWER';
      NO_LOAD_CHECK='Both';
      NO_IO_CHECK='Both';
      NO_ASSERT_CHECK='TRUE';
      NO_DIR_CHECK='TRUE';
      ALLOW_CONNECT='TRUE';
    'AVDD1P5'<1>:
      PIN_NUMBER='(47)';
      PINUSE='POWER';
      NO_LOAD_CHECK='Both';
      NO_IO_CHECK='Both';
      NO_ASSERT_CHECK='TRUE';
      NO_DIR_CHECK='TRUE';
      ALLOW_CONNECT='TRUE';
    'AVDD1P5'<0>:
      PIN_NUMBER='(56)';
      PINUSE='POWER';
      NO_LOAD_CHECK='Both';
      NO_IO_CHECK='Both';
      NO_ASSERT_CHECK='TRUE';
      NO_DIR_CHECK='TRUE';
      ALLOW_CONNECT='TRUE';
    'AVDD33':
      PIN_NUMBER='(51)';
      PINUSE='POWER';
      NO_LOAD_CHECK='Both';
      NO_IO_CHECK='Both';
      NO_ASSERT_CHECK='TRUE';
      NO_DIR_CHECK='TRUE';
      ALLOW_CONNECT='TRUE';
    'CBOT':
      PIN_NUMBER='(37)';
      PIN_TYPE='ANALOG';
      NO_LOAD_CHECK='Both';
      NO_IO_CHECK='Both';
      NO_ASSERT_CHECK='TRUE';
      NO_DIR_CHECK='TRUE';
      ALLOW_CONNECT='TRUE';
    'CTOP':
      PIN_NUMBER='(40)';
      PIN_TYPE='ANALOG';
      NO_LOAD_CHECK='Both';
      NO_IO_CHECK='Both';
      NO_ASSERT_CHECK='TRUE';
      NO_DIR_CHECK='TRUE';
      ALLOW_CONNECT='TRUE';
    'DEV_OFF_N':
      PIN_NUMBER='(28)';
      INPUT_LOAD='(-0.01,0.01)';
    'JTAG_CLK':
      PIN_NUMBER='(19)';
      INPUT_LOAD='(-0.01,0.01)';
    'JTAG_TDI':
      PIN_NUMBER='(29)';
      INPUT_LOAD='(-0.01,0.01)';
    'JTAG_TDO':
      PIN_NUMBER='(4)';
      OUTPUT_LOAD='(1.0,-1.0)';
    'JTAG_TMS':
      PIN_NUMBER='(18)';
      INPUT_LOAD='(-0.01,0.01)';
    'LAN_PWR_GOOD':
      PIN_NUMBER='(1)';
      INPUT_LOAD='(-0.01,0.01)';
    'LED0':
      PIN_NUMBER='(31)';
      OUTPUT_LOAD='(1.0,-1.0)';
    'LED1':
      PIN_NUMBER='(30)';
      OUTPUT_LOAD='(1.0,-1.0)';
    'LED2':
      PIN_NUMBER='(33)';
      OUTPUT_LOAD='(1.0,-1.0)';
    'MDI_MINUS'<3>:
      PIN_NUMBER='(49)';
      BIDIRECTIONAL='TRUE';
      INPUT_LOAD='(-0.01,0.01)';
      OUTPUT_LOAD='(1.0,-1.0)';
    'MDI_MINUS'<2>:
      PIN_NUMBER='(52)';
      BIDIRECTIONAL='TRUE';
      INPUT_LOAD='(-0.01,0.01)';
      OUTPUT_LOAD='(1.0,-1.0)';
    'MDI_MINUS'<1>:
      PIN_NUMBER='(54)';
      BIDIRECTIONAL='TRUE';
      INPUT_LOAD='(-0.01,0.01)';
      OUTPUT_LOAD='(1.0,-1.0)';
    'MDI_MINUS'<0>:
      PIN_NUMBER='(57)';
      BIDIRECTIONAL='TRUE';
      INPUT_LOAD='(-0.01,0.01)';
      OUTPUT_LOAD='(1.0,-1.0)';
    'MDI_PLUS'<3>:
      PIN_NUMBER='(50)';
      BIDIRECTIONAL='TRUE';
      INPUT_LOAD='(-0.01,0.01)';
      OUTPUT_LOAD='(1.0,-1.0)';
    'MDI_PLUS'<2>:
      PIN_NUMBER='(53)';
      BIDIRECTIONAL='TRUE';
      INPUT_LOAD='(-0.01,0.01)';
      OUTPUT_LOAD='(1.0,-1.0)';
    'MDI_PLUS'<1>:
      PIN_NUMBER='(55)';
      BIDIRECTIONAL='TRUE';
      INPUT_LOAD='(-0.01,0.01)';
      OUTPUT_LOAD='(1.0,-1.0)';
    'MDI_PLUS'<0>:
      PIN_NUMBER='(58)';
      BIDIRECTIONAL='TRUE';
      INPUT_LOAD='(-0.01,0.01)';
      OUTPUT_LOAD='(1.0,-1.0)';
    'NC':
      PIN_NUMBER='(22)';
      INPUT_LOAD='(-0.01,0.01)';
      OUTPUT_LOAD='(1.0,-1.0)';
      OUTPUT_TYPE='(TS,TS)';
      BIDIRECTIONAL='TRUE';
      PIN_GROUP='1';
    'NC_SI_ARB_IN':
      PIN_NUMBER='(43)';
      INPUT_LOAD='(-0.01,0.01)';
    'NC_SI_ARB_OUT':
      PIN_NUMBER='(44)';
      OUTPUT_LOAD='(1.0,-1.0)';
    'NC_SI_CLK_IN':
      PIN_NUMBER='(2)';
      INPUT_LOAD='(-0.01,0.01)';
    'NC_SI_CRS_DV':
      PIN_NUMBER='(3)';
      OUTPUT_LOAD='(1.0,-1.0)';
    'NC_SI_RXD0':
      PIN_NUMBER='(6)';
      OUTPUT_LOAD='(1.0,-1.0)';
    'NC_SI_RXD1':
      PIN_NUMBER='(5)';
      OUTPUT_LOAD='(1.0,-1.0)';
    'NC_SI_TXD0':
      PIN_NUMBER='(9)';
      INPUT_LOAD='(-0.01,0.01)';
    'NC_SI_TXD1':
      PIN_NUMBER='(8)';
      INPUT_LOAD='(-0.01,0.01)';
    'NC_SI_TX_EN':
      PIN_NUMBER='(7)';
      INPUT_LOAD='(-0.01,0.01)';
    'NVM_CS_N':
      PIN_NUMBER='(15)';
      OUTPUT_LOAD='(1.0,-1.0)';
    'NVM_SI':
      PIN_NUMBER='(12)';
      OUTPUT_LOAD='(1.0,-1.0)';
    'NVM_SK':
      PIN_NUMBER='(13)';
      OUTPUT_LOAD='(1.0,-1.0)';
    'NVM_SO':
      PIN_NUMBER='(14)';
      INPUT_LOAD='(-0.01,0.01)';
    'PECLKN':
      PIN_NUMBER='(25)';
      INPUT_LOAD='(-0.01,0.01)';
    'PECLKP':
      PIN_NUMBER='(26)';
      INPUT_LOAD='(-0.01,0.01)';
    'PE_RN':
      PIN_NUMBER='(23)';
      INPUT_LOAD='(-0.01,0.01)';
    'PE_RP':
      PIN_NUMBER='(24)';
      INPUT_LOAD='(-0.01,0.01)';
    'PE_RST_N':
      PIN_NUMBER='(17)';
      INPUT_LOAD='(-0.01,0.01)';
    'PE_TN':
      PIN_NUMBER='(20)';
      OUTPUT_LOAD='(1.0,-1.0)';
    'PE_TP':
      PIN_NUMBER='(21)';
      OUTPUT_LOAD='(1.0,-1.0)';
    'PE_WAKE_N':
      PIN_NUMBER='(16)';
      BIDIRECTIONAL='TRUE';
      INPUT_LOAD='(-0.01,0.01)';
      OUTPUT_LOAD='(1.0,-1.0)';
    'RSET':
      PIN_NUMBER='(48)';
      INPUT_LOAD='(-0.01,0.01)';
      OUTPUT_LOAD='(1.0,-1.0)';
      OUTPUT_TYPE='(TS,TS)';
      BIDIRECTIONAL='TRUE';
      PIN_GROUP='1';
    'SDP0':
      PIN_NUMBER='(63)';
      BIDIRECTIONAL='TRUE';
      INPUT_LOAD='(-0.01,0.01)';
      OUTPUT_LOAD='(1.0,-1.0)';
    'SDP1':
      PIN_NUMBER='(61)';
      BIDIRECTIONAL='TRUE';
      INPUT_LOAD='(-0.01,0.01)';
      OUTPUT_LOAD='(1.0,-1.0)';
    'SDP2':
      PIN_NUMBER='(62)';
      BIDIRECTIONAL='TRUE';
      INPUT_LOAD='(-0.01,0.01)';
      OUTPUT_LOAD='(1.0,-1.0)';
    'SDP3':
      PIN_NUMBER='(60)';
      BIDIRECTIONAL='TRUE';
      INPUT_LOAD='(-0.01,0.01)';
      OUTPUT_LOAD='(1.0,-1.0)';
    'SMB_ALRT_N':
      PIN_NUMBER='(35)';
      OUTPUT_LOAD='(1.0,-1.0)';
    'SMB_CLK':
      PIN_NUMBER='(34)';
      BIDIRECTIONAL='TRUE';
      INPUT_LOAD='(-0.01,0.01)';
      OUTPUT_LOAD='(1.0,-1.0)';
    'SMB_DATA':
      PIN_NUMBER='(36)';
      BIDIRECTIONAL='TRUE';
      INPUT_LOAD='(-0.01,0.01)';
      OUTPUT_LOAD='(1.0,-1.0)';
    'THPAD':
      PIN_NUMBER='(65)';
      PINUSE='GROUND';
      NO_LOAD_CHECK='Both';
      NO_IO_CHECK='Both';
      NO_ASSERT_CHECK='TRUE';
      NO_DIR_CHECK='TRUE';
      ALLOW_CONNECT='TRUE';
    'VDD':
      PIN_NUMBER='(42)';
      PINUSE='POWER';
      NO_LOAD_CHECK='Both';
      NO_IO_CHECK='Both';
      NO_ASSERT_CHECK='TRUE';
      NO_DIR_CHECK='TRUE';
      ALLOW_CONNECT='TRUE';
    'VDD0P9'<2>:
      PIN_NUMBER='(11)';
      PINUSE='POWER';
      NO_LOAD_CHECK='Both';
      NO_IO_CHECK='Both';
      NO_ASSERT_CHECK='TRUE';
      NO_DIR_CHECK='TRUE';
      ALLOW_CONNECT='TRUE';
    'VDD0P9'<1>:
      PIN_NUMBER='(32)';
      PINUSE='POWER';
      NO_LOAD_CHECK='Both';
      NO_IO_CHECK='Both';
      NO_ASSERT_CHECK='TRUE';
      NO_DIR_CHECK='TRUE';
      ALLOW_CONNECT='TRUE';
    'VDD0P9'<0>:
      PIN_NUMBER='(59)';
      PINUSE='POWER';
      NO_LOAD_CHECK='Both';
      NO_IO_CHECK='Both';
      NO_ASSERT_CHECK='TRUE';
      NO_DIR_CHECK='TRUE';
      ALLOW_CONNECT='TRUE';
    'VDD3P3'<3>:
      PIN_NUMBER='(10)';
      PINUSE='POWER';
      NO_LOAD_CHECK='Both';
      NO_IO_CHECK='Both';
      NO_ASSERT_CHECK='TRUE';
      NO_DIR_CHECK='TRUE';
      ALLOW_CONNECT='TRUE';
    'VDD3P3'<2>:
      PIN_NUMBER='(27)';
      PINUSE='POWER';
      NO_LOAD_CHECK='Both';
      NO_IO_CHECK='Both';
      NO_ASSERT_CHECK='TRUE';
      NO_DIR_CHECK='TRUE';
      ALLOW_CONNECT='TRUE';
    'VDD3P3'<1>:
      PIN_NUMBER='(41)';
      PINUSE='POWER';
      NO_LOAD_CHECK='Both';
      NO_IO_CHECK='Both';
      NO_ASSERT_CHECK='TRUE';
      NO_DIR_CHECK='TRUE';
      ALLOW_CONNECT='TRUE';
    'VDD3P3'<0>:
      PIN_NUMBER='(64)';
      PINUSE='POWER';
      NO_LOAD_CHECK='Both';
      NO_IO_CHECK='Both';
      NO_ASSERT_CHECK='TRUE';
      NO_DIR_CHECK='TRUE';
      ALLOW_CONNECT='TRUE';
    'XTAL1':
      PIN_NUMBER='(46)';
      INPUT_LOAD='(-0.01,0.01)';
    'XTAL2':
      PIN_NUMBER='(45)';
      OUTPUT_LOAD='(1.0,-1.0)';
  end_pin;
  body
    PART_NAME='SPRINGVILLE';
    PHYS_DES_PREFIX='U';
  end_body;
end_primitive;

primitive 'SPRINGVILLE_SM1';
  pin
    'CBOT':
      PIN_NUMBER='(37)';
      PIN_TYPE='ANALOG';
      NO_LOAD_CHECK='Both';
      NO_IO_CHECK='Both';
      NO_ASSERT_CHECK='TRUE';
      NO_DIR_CHECK='TRUE';
      ALLOW_CONNECT='TRUE';
    'CTOP':
      PIN_NUMBER='(40)';
      PIN_TYPE='ANALOG';
      NO_LOAD_CHECK='Both';
      NO_IO_CHECK='Both';
      NO_ASSERT_CHECK='TRUE';
      NO_DIR_CHECK='TRUE';
      ALLOW_CONNECT='TRUE';
    'DEV_OFF_N':
      PIN_NUMBER='(28)';
      INPUT_LOAD='(-0.01,0.01)';
    'GND':
      PIN_NUMBER='(65)';
      PINUSE='GROUND';
      NO_LOAD_CHECK='Both';
      NO_IO_CHECK='Both';
      NO_ASSERT_CHECK='TRUE';
      NO_DIR_CHECK='TRUE';
      ALLOW_CONNECT='TRUE';
    'JTAG_CLK':
      PIN_NUMBER='(19)';
      INPUT_LOAD='(-0.01,0.01)';
    'JTAG_TDI':
      PIN_NUMBER='(29)';
      INPUT_LOAD='(-0.01,0.01)';
    'JTAG_TDO':
      PIN_NUMBER='(4)';
      OUTPUT_LOAD='(1.0,-1.0)';
    'JTAG_TMS':
      PIN_NUMBER='(18)';
      INPUT_LOAD='(-0.01,0.01)';
    'LAN_PWR_GOOD':
      PIN_NUMBER='(1)';
      INPUT_LOAD='(-0.01,0.01)';
    'LED0':
      PIN_NUMBER='(31)';
      OUTPUT_LOAD='(1.0,-1.0)';
    'LED1':
      PIN_NUMBER='(30)';
      OUTPUT_LOAD='(1.0,-1.0)';
    'LED2':
      PIN_NUMBER='(33)';
      OUTPUT_LOAD='(1.0,-1.0)';
    'MDI_MINUS0_SFP_I2C_DATA':
      PIN_NUMBER='(57)';
      BIDIRECTIONAL='TRUE';
      INPUT_LOAD='(-0.01,0.01)';
      OUTPUT_LOAD='(1.0,-1.0)';
    'MDI_MINUS1_SRDS_SIG_DET':
      PIN_NUMBER='(54)';
      BIDIRECTIONAL='TRUE';
      INPUT_LOAD='(-0.01,0.01)';
      OUTPUT_LOAD='(1.0,-1.0)';
    'MDI_MINUS2_SETN':
      PIN_NUMBER='(52)';
      BIDIRECTIONAL='TRUE';
      INPUT_LOAD='(-0.01,0.01)';
      OUTPUT_LOAD='(1.0,-1.0)';
    'MDI_MINUS3_SERN':
      PIN_NUMBER='(49)';
      BIDIRECTIONAL='TRUE';
      INPUT_LOAD='(-0.01,0.01)';
      OUTPUT_LOAD='(1.0,-1.0)';
    'MDI_PLUS0_NC':
      PIN_NUMBER='(58)';
      BIDIRECTIONAL='TRUE';
      INPUT_LOAD='(-0.01,0.01)';
      OUTPUT_LOAD='(1.0,-1.0)';
    'MDI_PLUS1_SFP_I2C_CLK':
      PIN_NUMBER='(55)';
      BIDIRECTIONAL='TRUE';
      INPUT_LOAD='(-0.01,0.01)';
      OUTPUT_LOAD='(1.0,-1.0)';
    'MDI_PLUS2_SETP':
      PIN_NUMBER='(53)';
      BIDIRECTIONAL='TRUE';
      INPUT_LOAD='(-0.01,0.01)';
      OUTPUT_LOAD='(1.0,-1.0)';
    'MDI_PLUS3_SERP':
      PIN_NUMBER='(50)';
      BIDIRECTIONAL='TRUE';
      INPUT_LOAD='(-0.01,0.01)';
      OUTPUT_LOAD='(1.0,-1.0)';
    'NC':
      PIN_NUMBER='(22)';
      INPUT_LOAD='(-0.01,0.01)';
    'NC_SI_ARB_IN':
      PIN_NUMBER='(43)';
      INPUT_LOAD='(-0.01,0.01)';
    'NC_SI_ARB_OUT':
      PIN_NUMBER='(44)';
      OUTPUT_LOAD='(1.0,-1.0)';
    'NC_SI_CLK_IN':
      PIN_NUMBER='(2)';
      INPUT_LOAD='(-0.01,0.01)';
    'NC_SI_CRS_DV':
      PIN_NUMBER='(3)';
      OUTPUT_LOAD='(1.0,-1.0)';
    'NC_SI_RXD0':
      PIN_NUMBER='(6)';
      OUTPUT_LOAD='(1.0,-1.0)';
    'NC_SI_RXD1':
      PIN_NUMBER='(5)';
      OUTPUT_LOAD='(1.0,-1.0)';
    'NC_SI_TXD0':
      PIN_NUMBER='(9)';
      INPUT_LOAD='(-0.01,0.01)';
    'NC_SI_TXD1':
      PIN_NUMBER='(8)';
      INPUT_LOAD='(-0.01,0.01)';
    'NC_SI_TX_EN':
      PIN_NUMBER='(7)';
      INPUT_LOAD='(-0.01,0.01)';
    'NVM_CS_N':
      PIN_NUMBER='(15)';
      OUTPUT_LOAD='(1.0,-1.0)';
    'NVM_SI':
      PIN_NUMBER='(12)';
      OUTPUT_LOAD='(1.0,-1.0)';
    'NVM_SK':
      PIN_NUMBER='(13)';
      OUTPUT_LOAD='(1.0,-1.0)';
    'NVM_SO':
      PIN_NUMBER='(14)';
      INPUT_LOAD='(-0.01,0.01)';
    'PECLKN':
      PIN_NUMBER='(25)';
      INPUT_LOAD='(-0.01,0.01)';
    'PECLKP':
      PIN_NUMBER='(26)';
      INPUT_LOAD='(-0.01,0.01)';
    'PE_RN':
      PIN_NUMBER='(23)';
      INPUT_LOAD='(-0.01,0.01)';
    'PE_RP':
      PIN_NUMBER='(24)';
      INPUT_LOAD='(-0.01,0.01)';
    'PE_RST_N':
      PIN_NUMBER='(17)';
      INPUT_LOAD='(-0.01,0.01)';
    'PE_TN':
      PIN_NUMBER='(20)';
      OUTPUT_LOAD='(1.0,-1.0)';
    'PE_TP':
      PIN_NUMBER='(21)';
      OUTPUT_LOAD='(1.0,-1.0)';
    'PE_WAKE_N':
      PIN_NUMBER='(16)';
      BIDIRECTIONAL='TRUE';
      INPUT_LOAD='(-0.01,0.01)';
      OUTPUT_LOAD='(1.0,-1.0)';
    'RSET':
      PIN_NUMBER='(48)';
      PIN_TYPE='ANALOG';
      NO_LOAD_CHECK='Both';
      NO_IO_CHECK='Both';
      NO_ASSERT_CHECK='TRUE';
      NO_DIR_CHECK='TRUE';
      ALLOW_CONNECT='TRUE';
    'SDP0':
      PIN_NUMBER='(63)';
      BIDIRECTIONAL='TRUE';
      INPUT_LOAD='(-0.01,0.01)';
      OUTPUT_LOAD='(1.0,-1.0)';
    'SDP1_PCIE_DIS_SDP1':
      PIN_NUMBER='(61)';
      BIDIRECTIONAL='TRUE';
      INPUT_LOAD='(-0.01,0.01)';
      OUTPUT_LOAD='(1.0,-1.0)';
    'SDP2':
      PIN_NUMBER='(62)';
      BIDIRECTIONAL='TRUE';
      INPUT_LOAD='(-0.01,0.01)';
      OUTPUT_LOAD='(1.0,-1.0)';
    'SDP3':
      PIN_NUMBER='(60)';
      BIDIRECTIONAL='TRUE';
      INPUT_LOAD='(-0.01,0.01)';
      OUTPUT_LOAD='(1.0,-1.0)';
    'SMB_ALRT_N':
      PIN_NUMBER='(35)';
      OUTPUT_LOAD='(1.0,-1.0)';
    'SMB_CLK':
      PIN_NUMBER='(34)';
      BIDIRECTIONAL='TRUE';
      INPUT_LOAD='(-0.01,0.01)';
      OUTPUT_LOAD='(1.0,-1.0)';
    'SMB_DATA':
      PIN_NUMBER='(36)';
      BIDIRECTIONAL='TRUE';
      INPUT_LOAD='(-0.01,0.01)';
      OUTPUT_LOAD='(1.0,-1.0)';
    'VDD0P9'<3>:
      PIN_NUMBER='(42)';
      PINUSE='POWER';
      NO_LOAD_CHECK='Both';
      NO_IO_CHECK='Both';
      NO_ASSERT_CHECK='TRUE';
      NO_DIR_CHECK='TRUE';
      ALLOW_CONNECT='TRUE';
    'VDD0P9'<2>:
      PIN_NUMBER='(11)';
      PINUSE='POWER';
      NO_LOAD_CHECK='Both';
      NO_IO_CHECK='Both';
      NO_ASSERT_CHECK='TRUE';
      NO_DIR_CHECK='TRUE';
      ALLOW_CONNECT='TRUE';
    'VDD0P9'<1>:
      PIN_NUMBER='(32)';
      PINUSE='POWER';
      NO_LOAD_CHECK='Both';
      NO_IO_CHECK='Both';
      NO_ASSERT_CHECK='TRUE';
      NO_DIR_CHECK='TRUE';
      ALLOW_CONNECT='TRUE';
    'VDD0P9'<0>:
      PIN_NUMBER='(59)';
      PINUSE='POWER';
      NO_LOAD_CHECK='Both';
      NO_IO_CHECK='Both';
      NO_ASSERT_CHECK='TRUE';
      NO_DIR_CHECK='TRUE';
      ALLOW_CONNECT='TRUE';
    'VDD0P9_OUT':
      PIN_NUMBER='(38)';
      PINUSE='POWER';
      NO_LOAD_CHECK='Both';
      NO_IO_CHECK='Both';
      NO_ASSERT_CHECK='TRUE';
      NO_DIR_CHECK='TRUE';
      ALLOW_CONNECT='TRUE';
    'VDD1P5'<1>:
      PIN_NUMBER='(47)';
      PINUSE='POWER';
      NO_LOAD_CHECK='Both';
      NO_IO_CHECK='Both';
      NO_ASSERT_CHECK='TRUE';
      NO_DIR_CHECK='TRUE';
      ALLOW_CONNECT='TRUE';
    'VDD1P5'<0>:
      PIN_NUMBER='(56)';
      PINUSE='POWER';
      NO_LOAD_CHECK='Both';
      NO_IO_CHECK='Both';
      NO_ASSERT_CHECK='TRUE';
      NO_DIR_CHECK='TRUE';
      ALLOW_CONNECT='TRUE';
    'VDD1P5_OUT':
      PIN_NUMBER='(39)';
      PINUSE='POWER';
      NO_LOAD_CHECK='Both';
      NO_IO_CHECK='Both';
      NO_ASSERT_CHECK='TRUE';
      NO_DIR_CHECK='TRUE';
      ALLOW_CONNECT='TRUE';
    'VDD3P3'<4>:
      PIN_NUMBER='(10)';
      PINUSE='POWER';
      NO_LOAD_CHECK='Both';
      NO_IO_CHECK='Both';
      NO_ASSERT_CHECK='TRUE';
      NO_DIR_CHECK='TRUE';
      ALLOW_CONNECT='TRUE';
    'VDD3P3'<3>:
      PIN_NUMBER='(27)';
      PINUSE='POWER';
      NO_LOAD_CHECK='Both';
      NO_IO_CHECK='Both';
      NO_ASSERT_CHECK='TRUE';
      NO_DIR_CHECK='TRUE';
      ALLOW_CONNECT='TRUE';
    'VDD3P3'<2>:
      PIN_NUMBER='(41)';
      PINUSE='POWER';
      NO_LOAD_CHECK='Both';
      NO_IO_CHECK='Both';
      NO_ASSERT_CHECK='TRUE';
      NO_DIR_CHECK='TRUE';
      ALLOW_CONNECT='TRUE';
    'VDD3P3'<1>:
      PIN_NUMBER='(51)';
      PINUSE='POWER';
      NO_LOAD_CHECK='Both';
      NO_IO_CHECK='Both';
      NO_ASSERT_CHECK='TRUE';
      NO_DIR_CHECK='TRUE';
      ALLOW_CONNECT='TRUE';
    'VDD3P3'<0>:
      PIN_NUMBER='(64)';
      PINUSE='POWER';
      NO_LOAD_CHECK='Both';
      NO_IO_CHECK='Both';
      NO_ASSERT_CHECK='TRUE';
      NO_DIR_CHECK='TRUE';
      ALLOW_CONNECT='TRUE';
    'XTAL1':
      PIN_NUMBER='(46)';
      INPUT_LOAD='(-0.01,0.01)';
    'XTAL2':
      PIN_NUMBER='(45)';
      OUTPUT_LOAD='(1.0,-1.0)';
  end_pin;
  body
    PART_NAME='SPRINGVILLE';
    PHYS_DES_PREFIX='EU';
  end_body;
end_primitive;

END.
